# T6G (Grand Teton) — schematic netlist excerpt (pin names and nets, part order shuffled) for the footprints in the layout excerpt that follows; sources: Cadence DE-HDL packaged netlist, KiCad conversion of 04192023_DAF0TMB3IC0_F0TG_MB_C_brd_V02_OCP.brd

J108  CONN112_10137002101LF  CONN112_10137002-101LF IO  pkg HSD_F112D8_P2W1-2_RDH  page 118
  A1  = GPU_3V3IO_RSVD3_FFU
  A2  = GND
  A3  = PRSNT_CABLE_GPU_A2_N
  A4  = GND
  A5  = GPU_3V3IO_RSVD5_FFU
  A6  = GND
  A7  = GPU_FPGA_OVERT_N
  A8  = GND
  B1  = GND
  B2  = P5E_CPU0_P0_RX_BUF_DN<1>
  B3  = GND
  B4  = P5E_CPU0_P0_RX_BUF_DN<3>
  B5  = GND
  B6  = P5E_CPU0_P0_RX_BUF_DN<5>
  B7  = GND
  B8  = P5E_CPU0_P0_RX_BUF_DN<7>
  C1  = P5E_CPU0_P0_RX_BUF_DN<0>
  C2  = P5E_CPU0_P0_RX_BUF_DP<1>
  C3  = P5E_CPU0_P0_RX_BUF_DN<2>
  C4  = P5E_CPU0_P0_RX_BUF_DP<3>
  C5  = P5E_CPU0_P0_RX_BUF_DN<4>
  C6  = P5E_CPU0_P0_RX_BUF_DP<5>
  C7  = P5E_CPU0_P0_RX_BUF_DN<6>
  C8  = P5E_CPU0_P0_RX_BUF_DP<7>
  D1  = P5E_CPU0_P0_RX_BUF_DP<0>
  D2  = GND
  D3  = P5E_CPU0_P0_RX_BUF_DP<2>
  D4  = GND
  D5  = P5E_CPU0_P0_RX_BUF_DP<4>
  D6  = GND
  D7  = P5E_CPU0_P0_RX_BUF_DP<6>
  D8  = GND
  E1  = GND
  E2  = P5E_CPU0_P1_RX_BUF_DN<1>
  E3  = GND
  E4  = P5E_CPU0_P1_RX_BUF_DN<3>
  E5  = GND
  E6  = P5E_CPU0_P1_RX_BUF_DN<5>
  E7  = GND
  E8  = P5E_CPU0_P1_RX_BUF_DN<7>
  F1  = P5E_CPU0_P1_RX_BUF_DN<0>
  F2  = P5E_CPU0_P1_RX_BUF_DP<1>
  F3  = P5E_CPU0_P1_RX_BUF_DN<2>
  F4  = P5E_CPU0_P1_RX_BUF_DP<3>
  F5  = P5E_CPU0_P1_RX_BUF_DN<4>
  F6  = P5E_CPU0_P1_RX_BUF_DP<5>
  F7  = P5E_CPU0_P1_RX_BUF_DN<6>
  F8  = P5E_CPU0_P1_RX_BUF_DP<7>
  G1  = P5E_CPU0_P1_RX_BUF_DP<0>
  G2  = GND
  G3  = P5E_CPU0_P1_RX_BUF_DP<2>
  G4  = GND
  G5  = P5E_CPU0_P1_RX_BUF_DP<4>
  G6  = GND
  G7  = P5E_CPU0_P1_RX_BUF_DP<6>
  G8  = GND
  H1  = GND
  H2  = P5E_CPU0_P0_TX_BUF_C_DN<1>
  H3  = GND
  H4  = P5E_CPU0_P0_TX_BUF_C_DN<3>
  H5  = GND
  H6  = P5E_CPU0_P0_TX_BUF_C_DN<5>
  H7  = GND
  H8  = P5E_CPU0_P0_TX_BUF_C_DN<7>
  I1  = P5E_CPU0_P0_TX_BUF_C_DN<0>
  I2  = P5E_CPU0_P0_TX_BUF_C_DP<1>
  I3  = P5E_CPU0_P0_TX_BUF_C_DN<2>
  I4  = P5E_CPU0_P0_TX_BUF_C_DP<3>
  I5  = P5E_CPU0_P0_TX_BUF_C_DN<4>
  I6  = P5E_CPU0_P0_TX_BUF_C_DP<5>
  I7  = P5E_CPU0_P0_TX_BUF_C_DN<6>
  I8  = P5E_CPU0_P0_TX_BUF_C_DP<7>
  J1  = P5E_CPU0_P0_TX_BUF_C_DP<0>
  J2  = GND
  J3  = P5E_CPU0_P0_TX_BUF_C_DP<2>
  J4  = GND
  J5  = P5E_CPU0_P0_TX_BUF_C_DP<4>
  J6  = GND
  J7  = P5E_CPU0_P0_TX_BUF_C_DP<6>
  J8  = GND
  K1  = GND
  K2  = P5E_CPU0_P1_TX_BUF_C_DN<1>
  K3  = GND
  K4  = P5E_CPU0_P1_TX_BUF_C_DN<3>
  K5  = GND
  K6  = P5E_CPU0_P1_TX_BUF_C_DN<5>
  K7  = GND
  K8  = P5E_CPU0_P1_TX_BUF_C_DN<7>
  L1  = P5E_CPU0_P1_TX_BUF_C_DN<0>
  L2  = P5E_CPU0_P1_TX_BUF_C_DP<1>
  L3  = P5E_CPU0_P1_TX_BUF_C_DN<2>
  L4  = P5E_CPU0_P1_TX_BUF_C_DP<3>
  L5  = P5E_CPU0_P1_TX_BUF_C_DN<4>
  L6  = P5E_CPU0_P1_TX_BUF_C_DP<5>
  L7  = P5E_CPU0_P1_TX_BUF_C_DN<6>
  L8  = P5E_CPU0_P1_TX_BUF_C_DP<7>
  M1  = P5E_CPU0_P1_TX_BUF_C_DP<0>
  M2  = GND
  M3  = P5E_CPU0_P1_TX_BUF_C_DP<2>
  M4  = GND
  M5  = P5E_CPU0_P1_TX_BUF_C_DP<4>
  M6  = GND
  M7  = P5E_CPU0_P1_TX_BUF_C_DP<6>
  M8  = GND
  N1  = GND
  N2  = NC_J108_N2
  N3  = GND
  N4  = NC_J108_N4
  N5  = GND
  N6  = NC_J108_N6
  N7  = GND
  N8  = PRSNT_CABLE_GPU_A3_N

(kicad_pcb
	(version 20260206)
	(generator "pcbnew")
	(generator_version "10.0")
	(general
		(thickness 1.6)
		(legacy_teardrops no)
	)
	(paper "A4")
	(title_block
		(title "04192023_DAF0TMB3IC0_F0TG_MB_C_brd_V02_OCP.brd")
		(comment 1 "Grand Teton / footprint 484 of 8354 (J108), pads 1-31 of 48")
	)
	(layers
		(0 "F.Cu" signal "TOP")
		(4 "In1.Cu" signal "GND")
		(6 "In2.Cu" signal "IN1")
		(8 "In3.Cu" signal "GND1")
		(10 "In4.Cu" signal "IN2")
		(12 "In5.Cu" signal "GND2")
		(14 "In6.Cu" signal "IN3")
		(16 "In7.Cu" signal "GND3")
		(18 "In8.Cu" signal "VCC")
		(20 "In9.Cu" signal "VCC1")
		(22 "In10.Cu" signal "GND4")
		(24 "In11.Cu" signal "IN4")
		(26 "In12.Cu" signal "GND5")
		(28 "In13.Cu" signal "IN5")
		(30 "In14.Cu" signal "GND6")
		(32 "In15.Cu" signal "IN6")
		(34 "In16.Cu" signal "GND7")
		(2 "B.Cu" signal "BOTTOM")
		(9 "F.Adhes" user "F.Adhesive")
		(11 "B.Adhes" user "B.Adhesive")
		(13 "F.Paste" user "Package Geometry/Pastemask Top")
		(15 "B.Paste" user "Package Geometry/Pastemask Bottom")
		(5 "F.SilkS" user "Ref Des/Silkscreen Top")
		(7 "B.SilkS" user "Ref Des/Silkscreen Bottom")
		(1 "F.Mask" user "Board Geometry/Soldermask Top")
		(3 "B.Mask" user "Board Geometry/Soldermask Bottom")
		(17 "Dwgs.User" user "User.Drawings")
		(19 "Cmts.User" user "User.Comments")
		(21 "Eco1.User" user "User.Eco1")
		(23 "Eco2.User" user "User.Eco2")
		(25 "Edge.Cuts" user "Board Geometry/Outline")
		(27 "Margin" user)
		(31 "F.CrtYd" user "Package Geometry/Place Bound Top")
		(29 "B.CrtYd" user "Package Geometry/Place Bound Bottom")
		(35 "F.Fab" user "Ref Des/Assembly Top")
		(33 "B.Fab" user "Ref Des/Assembly Bottom")
	)
	(footprint ""
		(layer "F.Cu")
		(at 314.649612 -440.489848)
		(property "Reference" "J108"
			(at -7.73303 17.692878 0)
			(unlocked yes)
			(layer "F.SilkS")
			(effects
				(font
					(size 0.7874 0.5842)
					(thickness 0.1524)
				)
				(justify left)
			)
		)
		(property "Value" ""
			(at 0 0 0)
			(layer "F.Fab")
			(effects
				(font
					(size 1.27 1.27)
				)
			)
		)
		(duplicate_pad_numbers_are_jumpers no)
		(pad "A1" thru_hole rect
			(at 0 0 180)
			(size 0.766318 0.766318)
			(drill 0.359918)
			(layers "*.Cu" "*.Mask")
			(remove_unused_layers no)
			(net "GPU_3V3IO_RSVD3_FFU")
			(clearance 0.0508)
			(thermal_gap 0.0508)
			(padstack
				(mode front_inner_back)
				(layer "Inner"
					(shape circle)
					(size 0.766318 0.766318)
					(clearance 0.0508)
				)
				(layer "B.Cu"
					(shape rect)
					(size 0.766318 0.766318)
					(clearance 0.0508)
				)
			)
		)
		(pad "A2" thru_hole circle
			(at 1.999996 0.199898 180)
			(size 0.906272 0.906272)
			(drill 0.499872)
			(layers "*.Cu" "*.Mask")
			(remove_unused_layers no)
			(net "GND")
			(clearance 0.0508)
			(thermal_gap 0.0508)
		)
		(pad "A3" thru_hole circle
			(at 3.999992 0 180)
			(size 0.766318 0.766318)
			(drill 0.359918)
			(layers "*.Cu" "*.Mask")
			(remove_unused_layers no)
			(net "PRSNT_CABLE_GPU_A2_N")
			(clearance 0.0508)
			(thermal_gap 0.0508)
		)
		(pad "A4" thru_hole circle
			(at 5.999988 0.199898 180)
			(size 0.906272 0.906272)
			(drill 0.499872)
			(layers "*.Cu" "*.Mask")
			(remove_unused_layers no)
			(net "GND")
			(clearance 0.0508)
			(thermal_gap 0.0508)
		)
		(pad "A5" thru_hole circle
			(at 7.999984 0 180)
			(size 0.766318 0.766318)
			(drill 0.359918)
			(layers "*.Cu" "*.Mask")
			(remove_unused_layers no)
			(net "GPU_3V3IO_RSVD5_FFU")
			(clearance 0.0508)
			(thermal_gap 0.0508)
		)
		(pad "A6" thru_hole circle
			(at 9.99998 0.199898 180)
			(size 0.906272 0.906272)
			(drill 0.499872)
			(layers "*.Cu" "*.Mask")
			(remove_unused_layers no)
			(net "GND")
			(clearance 0.0508)
			(thermal_gap 0.0508)
		)
		(pad "A7" thru_hole circle
			(at 11.999976 0 180)
			(size 0.766318 0.766318)
			(drill 0.359918)
			(layers "*.Cu" "*.Mask")
			(remove_unused_layers no)
			(net "GPU_FPGA_OVERT_N")
			(clearance 0.0508)
			(thermal_gap 0.0508)
		)
		(pad "A8" thru_hole circle
			(at 13.999972 0.199898 180)
			(size 0.906272 0.906272)
			(drill 0.499872)
			(layers "*.Cu" "*.Mask")
			(remove_unused_layers no)
			(net "GND")
			(clearance 0.0508)
			(thermal_gap 0.0508)
		)
		(pad "B1" thru_hole circle
			(at 0 1.199896 180)
			(size 0.906272 0.906272)
			(drill 0.499872)
			(layers "*.Cu" "*.Mask")
			(remove_unused_layers no)
			(net "GND")
			(clearance 0.0508)
			(thermal_gap 0.0508)
		)
		(pad "B3" thru_hole circle
			(at 3.999992 1.199896 180)
			(size 0.906272 0.906272)
			(drill 0.499872)
			(layers "*.Cu" "*.Mask")
			(remove_unused_layers no)
			(net "GND")
			(clearance 0.0508)
			(thermal_gap 0.0508)
		)
		(pad "B5" thru_hole circle
			(at 7.999984 1.199896 180)
			(size 0.906272 0.906272)
			(drill 0.499872)
			(layers "*.Cu" "*.Mask")
			(remove_unused_layers no)
			(net "GND")
			(clearance 0.0508)
			(thermal_gap 0.0508)
		)
		(pad "B7" thru_hole circle
			(at 11.999976 1.199896 180)
			(size 0.906272 0.906272)
			(drill 0.499872)
			(layers "*.Cu" "*.Mask")
			(remove_unused_layers no)
			(net "GND")
			(clearance 0.0508)
			(thermal_gap 0.0508)
		)
		(pad "D2" thru_hole circle
			(at 1.999996 3.800094 180)
			(size 0.906272 0.906272)
			(drill 0.499872)
			(layers "*.Cu" "*.Mask")
			(remove_unused_layers no)
			(net "GND")
			(clearance 0.0508)
			(thermal_gap 0.0508)
		)
		(pad "D4" thru_hole circle
			(at 5.999988 3.800094 180)
			(size 0.906272 0.906272)
			(drill 0.499872)
			(layers "*.Cu" "*.Mask")
			(remove_unused_layers no)
			(net "GND")
			(clearance 0.0508)
			(thermal_gap 0.0508)
		)
		(pad "D6" thru_hole circle
			(at 9.99998 3.800094 180)
			(size 0.906272 0.906272)
			(drill 0.499872)
			(layers "*.Cu" "*.Mask")
			(remove_unused_layers no)
			(net "GND")
			(clearance 0.0508)
			(thermal_gap 0.0508)
		)
		(pad "D8" thru_hole circle
			(at 13.999972 3.800094 180)
			(size 0.906272 0.906272)
			(drill 0.499872)
			(layers "*.Cu" "*.Mask")
			(remove_unused_layers no)
			(net "GND")
			(clearance 0.0508)
			(thermal_gap 0.0508)
		)
		(pad "E1" thru_hole circle
			(at 0 4.800092 180)
			(size 0.906272 0.906272)
			(drill 0.499872)
			(layers "*.Cu" "*.Mask")
			(remove_unused_layers no)
			(net "GND")
			(clearance 0.0508)
			(thermal_gap 0.0508)
		)
		(pad "E3" thru_hole circle
			(at 3.999992 4.800092 180)
			(size 0.906272 0.906272)
			(drill 0.499872)
			(layers "*.Cu" "*.Mask")
			(remove_unused_layers no)
			(net "GND")
			(clearance 0.0508)
			(thermal_gap 0.0508)
		)
		(pad "E5" thru_hole circle
			(at 7.999984 4.800092 180)
			(size 0.906272 0.906272)
			(drill 0.499872)
			(layers "*.Cu" "*.Mask")
			(remove_unused_layers no)
			(net "GND")
			(clearance 0.0508)
			(thermal_gap 0.0508)
		)
		(pad "E7" thru_hole circle
			(at 11.999976 4.800092 180)
			(size 0.906272 0.906272)
			(drill 0.499872)
			(layers "*.Cu" "*.Mask")
			(remove_unused_layers no)
			(net "GND")
			(clearance 0.0508)
			(thermal_gap 0.0508)
		)
		(pad "G2" thru_hole circle
			(at 1.999996 7.400036 180)
			(size 0.906272 0.906272)
			(drill 0.499872)
			(layers "*.Cu" "*.Mask")
			(remove_unused_layers no)
			(net "GND")
			(clearance 0.0508)
			(thermal_gap 0.0508)
		)
		(pad "G4" thru_hole circle
			(at 5.999988 7.400036 180)
			(size 0.906272 0.906272)
			(drill 0.499872)
			(layers "*.Cu" "*.Mask")
			(remove_unused_layers no)
			(net "GND")
			(clearance 0.0508)
			(thermal_gap 0.0508)
		)
		(pad "G6" thru_hole circle
			(at 9.99998 7.400036 180)
			(size 0.906272 0.906272)
			(drill 0.499872)
			(layers "*.Cu" "*.Mask")
			(remove_unused_layers no)
			(net "GND")
			(clearance 0.0508)
			(thermal_gap 0.0508)
		)
		(pad "G8" thru_hole circle
			(at 13.999972 7.400036 180)
			(size 0.906272 0.906272)
			(drill 0.499872)
			(layers "*.Cu" "*.Mask")
			(remove_unused_layers no)
			(net "GND")
			(clearance 0.0508)
			(thermal_gap 0.0508)
		)
		(pad "H1" thru_hole circle
			(at 0 8.400034 180)
			(size 0.906272 0.906272)
			(drill 0.499872)
			(layers "*.Cu" "*.Mask")
			(remove_unused_layers no)
			(net "GND")
			(clearance 0.0508)
			(thermal_gap 0.0508)
		)
		(pad "H3" thru_hole circle
			(at 3.999992 8.400034 180)
			(size 0.906272 0.906272)
			(drill 0.499872)
			(layers "*.Cu" "*.Mask")
			(remove_unused_layers no)
			(net "GND")
			(clearance 0.0508)
			(thermal_gap 0.0508)
		)
		(pad "H5" thru_hole circle
			(at 7.999984 8.400034 180)
			(size 0.906272 0.906272)
			(drill 0.499872)
			(layers "*.Cu" "*.Mask")
			(remove_unused_layers no)
			(net "GND")
			(clearance 0.0508)
			(thermal_gap 0.0508)
		)
		(pad "H7" thru_hole circle
			(at 11.999976 8.400034 180)
			(size 0.906272 0.906272)
			(drill 0.499872)
			(layers "*.Cu" "*.Mask")
			(remove_unused_layers no)
			(net "GND")
			(clearance 0.0508)
			(thermal_gap 0.0508)
		)
		(pad "J2" thru_hole circle
			(at 1.999996 10.999978 180)
			(size 0.906272 0.906272)
			(drill 0.499872)
			(layers "*.Cu" "*.Mask")
			(remove_unused_layers no)
			(net "GND")
			(clearance 0.0508)
			(thermal_gap 0.0508)
		)
		(pad "J4" thru_hole circle
			(at 5.999988 10.999978 180)
			(size 0.906272 0.906272)
			(drill 0.499872)
			(layers "*.Cu" "*.Mask")
			(remove_unused_layers no)
			(net "GND")
			(clearance 0.0508)
			(thermal_gap 0.0508)
		)
		(pad "J6" thru_hole circle
			(at 9.99998 10.999978 180)
			(size 0.906272 0.906272)
			(drill 0.499872)
			(layers "*.Cu" "*.Mask")
			(remove_unused_layers no)
			(net "GND")
			(clearance 0.0508)
			(thermal_gap 0.0508)
		)
	)
)
